(kicad_pcb
	(version 20260206)
	(generator "pcbnew")
	(generator_version "10.0")
	(general
		(thickness 1.6)
		(legacy_teardrops no)
	)
	(paper "A4")
	(title_block
		(title "01162023_DA0F0TEBIF0_F0T_Expander_BD_F_brd_V02_OCP.brd")
		(comment 1 "Grand Teton / footprints 5599-5604 of 9728")
	)
	(layers
		(0 "F.Cu" signal "TOP")
		(4 "In1.Cu" signal "GND")
		(6 "In2.Cu" signal "VCC")
		(8 "In3.Cu" signal "VCC1")
		(10 "In4.Cu" signal "GND1")
		(12 "In5.Cu" signal "IN1")
		(14 "In6.Cu" signal "GND2")
		(16 "In7.Cu" signal "IN2")
		(18 "In8.Cu" signal "GND3")
		(20 "In9.Cu" signal "IN3")
		(22 "In10.Cu" signal "GND4")
		(24 "In11.Cu" signal "IN4")
		(26 "In12.Cu" signal "GND5")
		(28 "In13.Cu" signal "IN5")
		(30 "In14.Cu" signal "GND6")
		(32 "In15.Cu" signal "IN6")
		(34 "In16.Cu" signal "GND7")
		(2 "B.Cu" signal "BOTTOM")
		(9 "F.Adhes" user "F.Adhesive")
		(11 "B.Adhes" user "B.Adhesive")
		(13 "F.Paste" user "Package Geometry/Pastemask Top")
		(15 "B.Paste" user "Package Geometry/Pastemask Bottom")
		(5 "F.SilkS" user "Ref Des/Silkscreen Top")
		(7 "B.SilkS" user "Ref Des/Silkscreen Bottom")
		(1 "F.Mask" user "Board Geometry/Soldermask Top")
		(3 "B.Mask" user "Board Geometry/Soldermask Bottom")
		(17 "Dwgs.User" user "User.Drawings")
		(19 "Cmts.User" user "User.Comments")
		(21 "Eco1.User" user "User.Eco1")
		(23 "Eco2.User" user "User.Eco2")
		(25 "Edge.Cuts" user "Board Geometry/Outline")
		(27 "Margin" user)
		(31 "F.CrtYd" user "Package Geometry/Place Bound Top")
		(29 "B.CrtYd" user "Package Geometry/Place Bound Bottom")
		(35 "F.Fab" user "Ref Des/Assembly Top")
		(33 "B.Fab" user "Ref Des/Assembly Bottom")
	)
	(footprint ""
		(layer "F.Cu")
		(at 3.608578 -381.411226)
		(property "Reference" "R6735"
			(at 0 0 0)
			(layer "F.SilkS")
			(hide yes)
			(effects
				(font
					(size 1.27 1.27)
				)
			)
		)
		(property "Value" ""
			(at 0 0 0)
			(layer "F.Fab")
			(effects
				(font
					(size 1.27 1.27)
				)
			)
		)
		(duplicate_pad_numbers_are_jumpers no)
		(fp_line
			(start -0.7874 -0.4064)
			(end 0.7874 -0.4064)
			(stroke
				(width 0.1524)
				(type default)
			)
			(layer "F.SilkS")
		)
		(fp_line
			(start -0.7874 0.4064)
			(end -0.7874 -0.4064)
			(stroke
				(width 0.1524)
				(type default)
			)
			(layer "F.SilkS")
		)
		(fp_line
			(start 0.7874 -0.4064)
			(end 0.7874 0.4064)
			(stroke
				(width 0.1524)
				(type default)
			)
			(layer "F.SilkS")
		)
		(fp_line
			(start 0.7874 0.4064)
			(end -0.7874 0.4064)
			(stroke
				(width 0.1524)
				(type default)
			)
			(layer "F.SilkS")
		)
		(fp_line
			(start -0.67945 -0.305054)
			(end -0.12065 -0.305054)
			(stroke
				(width 0.1)
				(type default)
			)
			(layer "F.Fab")
		)
		(fp_line
			(start -0.67945 0.3048)
			(end -0.67945 -0.305054)
			(stroke
				(width 0.1)
				(type default)
			)
			(layer "F.Fab")
		)
		(fp_line
			(start -0.12065 -0.305054)
			(end -0.12065 -0.2794)
			(stroke
				(width 0.1)
				(type default)
			)
			(layer "F.Fab")
		)
		(fp_line
			(start -0.12065 -0.2794)
			(end 0.12065 -0.2794)
			(stroke
				(width 0.1)
				(type default)
			)
			(layer "F.Fab")
		)
		(fp_line
			(start -0.12065 0.2794)
			(end -0.12065 0.3048)
			(stroke
				(width 0.1)
				(type default)
			)
			(layer "F.Fab")
		)
		(fp_line
			(start -0.12065 0.3048)
			(end -0.67945 0.3048)
			(stroke
				(width 0.1)
				(type default)
			)
			(layer "F.Fab")
		)
		(fp_line
			(start 0.120396 0.2794)
			(end -0.12065 0.2794)
			(stroke
				(width 0.1)
				(type default)
			)
			(layer "F.Fab")
		)
		(fp_line
			(start 0.120396 0.3048)
			(end 0.120396 0.2794)
			(stroke
				(width 0.1)
				(type default)
			)
			(layer "F.Fab")
		)
		(fp_line
			(start 0.12065 -0.3048)
			(end 0.67945 -0.3048)
			(stroke
				(width 0.1)
				(type default)
			)
			(layer "F.Fab")
		)
		(fp_line
			(start 0.12065 -0.2794)
			(end 0.12065 -0.3048)
			(stroke
				(width 0.1)
				(type default)
			)
			(layer "F.Fab")
		)
		(fp_line
			(start 0.67945 -0.3048)
			(end 0.67945 0.3048)
			(stroke
				(width 0.1)
				(type default)
			)
			(layer "F.Fab")
		)
		(fp_line
			(start 0.67945 0.3048)
			(end 0.120396 0.3048)
			(stroke
				(width 0.1)
				(type default)
			)
			(layer "F.Fab")
		)
		(pad "1" smd circle
			(at -0.40005 0)
			(size 0 0)
			(layers "F.Cu" "F.Mask" "F.Paste")
			(net "BIC_USB_8042_HUB_XOUT")
		)
		(pad "2" smd circle
			(at 0.40005 0)
			(size 0 0)
			(layers "F.Cu" "F.Mask" "F.Paste")
			(net "BIC_USB_8042_HUB_XIN")
		)
	)
	(footprint ""
		(layer "F.Cu")
		(at 248.971562 -214.035386 180)
		(property "Reference" "C2850"
			(at 0 0 180)
			(layer "F.SilkS")
			(hide yes)
			(effects
				(font
					(size 1.27 1.27)
				)
			)
		)
		(property "Value" ""
			(at 0 0 180)
			(layer "F.Fab")
			(effects
				(font
					(size 1.27 1.27)
				)
			)
		)
		(duplicate_pad_numbers_are_jumpers no)
		(fp_line
			(start 1.524 0.762)
			(end -1.524 0.762)
			(stroke
				(width 0.1524)
				(type default)
			)
			(layer "F.SilkS")
		)
		(fp_line
			(start 1.524 -0.762)
			(end 1.524 0.762)
			(stroke
				(width 0.1524)
				(type default)
			)
			(layer "F.SilkS")
		)
		(fp_line
			(start -1.524 0.762)
			(end -1.524 -0.762)
			(stroke
				(width 0.1524)
				(type default)
			)
			(layer "F.SilkS")
		)
		(fp_line
			(start -1.524 -0.762)
			(end 1.524 -0.762)
			(stroke
				(width 0.1524)
				(type default)
			)
			(layer "F.SilkS")
		)
		(fp_line
			(start 1.1049 0.724916)
			(end 1.1049 -0.724916)
			(stroke
				(width 0.1)
				(type default)
			)
			(layer "F.Fab")
		)
		(fp_line
			(start 1.1049 -0.724916)
			(end -1.1049 -0.724916)
			(stroke
				(width 0.1)
				(type default)
			)
			(layer "F.Fab")
		)
		(fp_line
			(start -1.1049 0.724916)
			(end 1.1049 0.724916)
			(stroke
				(width 0.1)
				(type default)
			)
			(layer "F.Fab")
		)
		(fp_line
			(start -1.1049 -0.724916)
			(end -1.1049 0.724916)
			(stroke
				(width 0.1)
				(type default)
			)
			(layer "F.Fab")
		)
		(pad "1" smd rect
			(at -0.889 0)
			(size 1.016 1.27)
			(layers "F.Cu" "F.Mask" "F.Paste")
			(net "P1V2_AUX")
		)
		(pad "2" smd rect
			(at 0.889 0)
			(size 1.016 1.27)
			(layers "F.Cu" "F.Mask" "F.Paste")
			(net "GND")
		)
	)
	(footprint ""
		(layer "F.Cu")
		(at 21.961094 -37.951156)
		(property "Reference" "Q134"
			(at 0.06096 -2.232406 0)
			(unlocked yes)
			(layer "F.SilkS")
			(effects
				(font
					(size 0.7874 0.5842)
					(thickness 0.1524)
				)
			)
		)
		(property "Value" ""
			(at 0 0 0)
			(layer "F.Fab")
			(effects
				(font
					(size 1.27 1.27)
				)
			)
		)
		(duplicate_pad_numbers_are_jumpers no)
		(fp_line
			(start -1.376172 -1.199896)
			(end -0.508 -1.199896)
			(stroke
				(width 0.1524)
				(type default)
			)
			(layer "F.SilkS")
		)
		(fp_line
			(start -1.376172 1.199896)
			(end -1.376172 -1.199896)
			(stroke
				(width 0.1524)
				(type default)
			)
			(layer "F.SilkS")
		)
		(fp_line
			(start -0.508 -1.199896)
			(end 0 -0.762)
			(stroke
				(width 0.1524)
				(type default)
			)
			(layer "F.SilkS")
		)
		(fp_line
			(start 0 -0.762)
			(end 0.508 -1.199896)
			(stroke
				(width 0.1524)
				(type default)
			)
			(layer "F.SilkS")
		)
		(fp_line
			(start 0.508 -1.199896)
			(end 1.376172 -1.199896)
			(stroke
				(width 0.1524)
				(type default)
			)
			(layer "F.SilkS")
		)
		(fp_line
			(start 1.376172 -1.199896)
			(end 1.376172 1.199896)
			(stroke
				(width 0.1524)
				(type default)
			)
			(layer "F.SilkS")
		)
		(fp_line
			(start 1.376172 1.199896)
			(end -1.376172 1.199896)
			(stroke
				(width 0.1524)
				(type default)
			)
			(layer "F.SilkS")
		)
		(fp_poly
			(pts
				(xy -1.44399 -1.086104) (xy -1.71323 -1.894332) (xy -2.252218 -1.355598)
			)
			(stroke
				(width 0)
				(type default)
			)
			(fill yes)
			(layer "F.SilkS")
		)
		(fp_line
			(start -0.674878 -1.100074)
			(end 0.674878 -1.100074)
			(stroke
				(width 0.1)
				(type default)
			)
			(layer "F.Fab")
		)
		(fp_line
			(start -0.674878 1.100074)
			(end -0.674878 -1.100074)
			(stroke
				(width 0.1)
				(type default)
			)
			(layer "F.Fab")
		)
		(fp_line
			(start 0.674878 -1.100074)
			(end 0.674878 1.100074)
			(stroke
				(width 0.1)
				(type default)
			)
			(layer "F.Fab")
		)
		(fp_line
			(start 0.674878 1.100074)
			(end -0.674878 1.100074)
			(stroke
				(width 0.1)
				(type default)
			)
			(layer "F.Fab")
		)
		(fp_poly
			(pts
				(xy -1.4605 -0.7493) (xy -2.2225 -1.1303) (xy -2.2225 -0.3683)
			)
			(stroke
				(width 0)
				(type default)
			)
			(fill yes)
			(layer "F.Fab")
		)
		(pad "1" smd rect
			(at -0.899922 -0.750062 270)
			(size 0.6096 0.6096)
			(layers "F.Cu" "F.Mask" "F.Paste")
			(net "GND")
		)
		(pad "2" smd rect
			(at -0.899922 0 270)
			(size 0.4064 0.6096)
			(layers "F.Cu" "F.Mask" "F.Paste")
			(net "P3V3_SSD1_PG_G1")
		)
		(pad "3" smd rect
			(at -0.899922 0.750062 270)
			(size 0.6096 0.6096)
			(layers "F.Cu" "F.Mask" "F.Paste")
			(net "PWRGD_P3V3_SSD1_D")
		)
		(pad "4" smd rect
			(at 0.899922 0.750062 270)
			(size 0.6096 0.6096)
			(layers "F.Cu" "F.Mask" "F.Paste")
			(net "GND")
		)
		(pad "5" smd rect
			(at 0.899922 0 270)
			(size 0.4064 0.6096)
			(layers "F.Cu" "F.Mask" "F.Paste")
			(net "P3V3_SSD1_PG_G2")
		)
		(pad "6" smd rect
			(at 0.899922 -0.750062 270)
			(size 0.6096 0.6096)
			(layers "F.Cu" "F.Mask" "F.Paste")
			(net "P3V3_SSD1_PG_G2")
		)
	)
	(footprint ""
		(layer "F.Cu")
		(at 418.93871 -22.867366 90)
		(property "Reference" "C3971"
			(at 0 0 90)
			(layer "F.SilkS")
			(hide yes)
			(effects
				(font
					(size 1.27 1.27)
				)
			)
		)
		(property "Value" ""
			(at 0 0 90)
			(layer "F.Fab")
			(effects
				(font
					(size 1.27 1.27)
				)
			)
		)
		(duplicate_pad_numbers_are_jumpers no)
		(fp_line
			(start 0.7874 -0.4064)
			(end 0.7874 0.4064)
			(stroke
				(width 0.1524)
				(type default)
			)
			(layer "F.SilkS")
		)
		(fp_line
			(start -0.7874 -0.4064)
			(end 0.7874 -0.4064)
			(stroke
				(width 0.1524)
				(type default)
			)
			(layer "F.SilkS")
		)
		(fp_line
			(start 0.7874 0.4064)
			(end -0.7874 0.4064)
			(stroke
				(width 0.1524)
				(type default)
			)
			(layer "F.SilkS")
		)
		(fp_line
			(start -0.7874 0.4064)
			(end -0.7874 -0.4064)
			(stroke
				(width 0.1524)
				(type default)
			)
			(layer "F.SilkS")
		)
		(fp_line
			(start -0.12065 -0.305054)
			(end -0.12065 -0.2794)
			(stroke
				(width 0.1)
				(type default)
			)
			(layer "F.Fab")
		)
		(fp_line
			(start -0.67945 -0.305054)
			(end -0.12065 -0.305054)
			(stroke
				(width 0.1)
				(type default)
			)
			(layer "F.Fab")
		)
		(fp_line
			(start 0.67945 -0.3048)
			(end 0.67945 0.3048)
			(stroke
				(width 0.1)
				(type default)
			)
			(layer "F.Fab")
		)
		(fp_line
			(start 0.12065 -0.3048)
			(end 0.67945 -0.3048)
			(stroke
				(width 0.1)
				(type default)
			)
			(layer "F.Fab")
		)
		(fp_line
			(start 0.12065 -0.2794)
			(end 0.12065 -0.3048)
			(stroke
				(width 0.1)
				(type default)
			)
			(layer "F.Fab")
		)
		(fp_line
			(start -0.12065 -0.2794)
			(end 0.12065 -0.2794)
			(stroke
				(width 0.1)
				(type default)
			)
			(layer "F.Fab")
		)
		(fp_line
			(start 0.120396 0.2794)
			(end -0.12065 0.2794)
			(stroke
				(width 0.1)
				(type default)
			)
			(layer "F.Fab")
		)
		(fp_line
			(start -0.12065 0.2794)
			(end -0.12065 0.3048)
			(stroke
				(width 0.1)
				(type default)
			)
			(layer "F.Fab")
		)
		(fp_line
			(start 0.67945 0.3048)
			(end 0.120396 0.3048)
			(stroke
				(width 0.1)
				(type default)
			)
			(layer "F.Fab")
		)
		(fp_line
			(start 0.120396 0.3048)
			(end 0.120396 0.2794)
			(stroke
				(width 0.1)
				(type default)
			)
			(layer "F.Fab")
		)
		(fp_line
			(start -0.12065 0.3048)
			(end -0.67945 0.3048)
			(stroke
				(width 0.1)
				(type default)
			)
			(layer "F.Fab")
		)
		(fp_line
			(start -0.67945 0.3048)
			(end -0.67945 -0.305054)
			(stroke
				(width 0.1)
				(type default)
			)
			(layer "F.Fab")
		)
		(pad "1" smd circle
			(at -0.40005 0 90)
			(size 0 0)
			(layers "F.Cu" "F.Mask" "F.Paste")
			(net "P12V_SSD14")
		)
		(pad "2" smd circle
			(at 0.40005 0 90)
			(size 0 0)
			(layers "F.Cu" "F.Mask" "F.Paste")
			(net "GND")
		)
	)
	(footprint ""
		(layer "F.Cu")
		(at 303.854612 -22.867366 90)
		(property "Reference" "C3943"
			(at 0 0 90)
			(layer "F.SilkS")
			(hide yes)
			(effects
				(font
					(size 1.27 1.27)
				)
			)
		)
		(property "Value" ""
			(at 0 0 90)
			(layer "F.Fab")
			(effects
				(font
					(size 1.27 1.27)
				)
			)
		)
		(duplicate_pad_numbers_are_jumpers no)
		(fp_line
			(start 0.7874 -0.4064)
			(end 0.7874 0.4064)
			(stroke
				(width 0.1524)
				(type default)
			)
			(layer "F.SilkS")
		)
		(fp_line
			(start -0.7874 -0.4064)
			(end 0.7874 -0.4064)
			(stroke
				(width 0.1524)
				(type default)
			)
			(layer "F.SilkS")
		)
		(fp_line
			(start 0.7874 0.4064)
			(end -0.7874 0.4064)
			(stroke
				(width 0.1524)
				(type default)
			)
			(layer "F.SilkS")
		)
		(fp_line
			(start -0.7874 0.4064)
			(end -0.7874 -0.4064)
			(stroke
				(width 0.1524)
				(type default)
			)
			(layer "F.SilkS")
		)
		(fp_line
			(start -0.12065 -0.305054)
			(end -0.12065 -0.2794)
			(stroke
				(width 0.1)
				(type default)
			)
			(layer "F.Fab")
		)
		(fp_line
			(start -0.67945 -0.305054)
			(end -0.12065 -0.305054)
			(stroke
				(width 0.1)
				(type default)
			)
			(layer "F.Fab")
		)
		(fp_line
			(start 0.67945 -0.3048)
			(end 0.67945 0.3048)
			(stroke
				(width 0.1)
				(type default)
			)
			(layer "F.Fab")
		)
		(fp_line
			(start 0.12065 -0.3048)
			(end 0.67945 -0.3048)
			(stroke
				(width 0.1)
				(type default)
			)
			(layer "F.Fab")
		)
		(fp_line
			(start 0.12065 -0.2794)
			(end 0.12065 -0.3048)
			(stroke
				(width 0.1)
				(type default)
			)
			(layer "F.Fab")
		)
		(fp_line
			(start -0.12065 -0.2794)
			(end 0.12065 -0.2794)
			(stroke
				(width 0.1)
				(type default)
			)
			(layer "F.Fab")
		)
		(fp_line
			(start 0.120396 0.2794)
			(end -0.12065 0.2794)
			(stroke
				(width 0.1)
				(type default)
			)
			(layer "F.Fab")
		)
		(fp_line
			(start -0.12065 0.2794)
			(end -0.12065 0.3048)
			(stroke
				(width 0.1)
				(type default)
			)
			(layer "F.Fab")
		)
		(fp_line
			(start 0.67945 0.3048)
			(end 0.120396 0.3048)
			(stroke
				(width 0.1)
				(type default)
			)
			(layer "F.Fab")
		)
		(fp_line
			(start 0.120396 0.3048)
			(end 0.120396 0.2794)
			(stroke
				(width 0.1)
				(type default)
			)
			(layer "F.Fab")
		)
		(fp_line
			(start -0.12065 0.3048)
			(end -0.67945 0.3048)
			(stroke
				(width 0.1)
				(type default)
			)
			(layer "F.Fab")
		)
		(fp_line
			(start -0.67945 0.3048)
			(end -0.67945 -0.305054)
			(stroke
				(width 0.1)
				(type default)
			)
			(layer "F.Fab")
		)
		(pad "1" smd circle
			(at -0.40005 0 90)
			(size 0 0)
			(layers "F.Cu" "F.Mask" "F.Paste")
			(net "P12V_SSD10")
		)
		(pad "2" smd circle
			(at 0.40005 0 90)
			(size 0 0)
			(layers "F.Cu" "F.Mask" "F.Paste")
			(net "GND")
		)
	)
	(footprint ""
		(layer "F.Cu")
		(at 244.196616 -306.681632 -90)
		(property "Reference" "PR177"
			(at 0 0 270)
			(layer "F.SilkS")
			(hide yes)
			(effects
				(font
					(size 1.27 1.27)
				)
			)
		)
		(property "Value" ""
			(at 0 0 270)
			(layer "F.Fab")
			(effects
				(font
					(size 1.27 1.27)
				)
			)
		)
		(duplicate_pad_numbers_are_jumpers no)
		(fp_line
			(start -0.7874 0.4064)
			(end -0.7874 -0.4064)
			(stroke
				(width 0.1524)
				(type default)
			)
			(layer "F.SilkS")
		)
		(fp_line
			(start 0.7874 0.4064)
			(end -0.7874 0.4064)
			(stroke
				(width 0.1524)
				(type default)
			)
			(layer "F.SilkS")
		)
		(fp_line
			(start -0.7874 -0.4064)
			(end 0.7874 -0.4064)
			(stroke
				(width 0.1524)
				(type default)
			)
			(layer "F.SilkS")
		)
		(fp_line
			(start 0.7874 -0.4064)
			(end 0.7874 0.4064)
			(stroke
				(width 0.1524)
				(type default)
			)
			(layer "F.SilkS")
		)
		(fp_line
			(start -0.67945 0.3048)
			(end -0.67945 -0.305054)
			(stroke
				(width 0.1)
				(type default)
			)
			(layer "F.Fab")
		)
		(fp_line
			(start -0.12065 0.3048)
			(end -0.67945 0.3048)
			(stroke
				(width 0.1)
				(type default)
			)
			(layer "F.Fab")
		)
		(fp_line
			(start 0.120396 0.3048)
			(end 0.120396 0.2794)
			(stroke
				(width 0.1)
				(type default)
			)
			(layer "F.Fab")
		)
		(fp_line
			(start 0.67945 0.3048)
			(end 0.120396 0.3048)
			(stroke
				(width 0.1)
				(type default)
			)
			(layer "F.Fab")
		)
		(fp_line
			(start -0.12065 0.2794)
			(end -0.12065 0.3048)
			(stroke
				(width 0.1)
				(type default)
			)
			(layer "F.Fab")
		)
		(fp_line
			(start 0.120396 0.2794)
			(end -0.12065 0.2794)
			(stroke
				(width 0.1)
				(type default)
			)
			(layer "F.Fab")
		)
		(fp_line
			(start -0.12065 -0.2794)
			(end 0.12065 -0.2794)
			(stroke
				(width 0.1)
				(type default)
			)
			(layer "F.Fab")
		)
		(fp_line
			(start 0.12065 -0.2794)
			(end 0.12065 -0.3048)
			(stroke
				(width 0.1)
				(type default)
			)
			(layer "F.Fab")
		)
		(fp_line
			(start 0.12065 -0.3048)
			(end 0.67945 -0.3048)
			(stroke
				(width 0.1)
				(type default)
			)
			(layer "F.Fab")
		)
		(fp_line
			(start 0.67945 -0.3048)
			(end 0.67945 0.3048)
			(stroke
				(width 0.1)
				(type default)
			)
			(layer "F.Fab")
		)
		(fp_line
			(start -0.67945 -0.305054)
			(end -0.12065 -0.305054)
			(stroke
				(width 0.1)
				(type default)
			)
			(layer "F.Fab")
		)
		(fp_line
			(start -0.12065 -0.305054)
			(end -0.12065 -0.2794)
			(stroke
				(width 0.1)
				(type default)
			)
			(layer "F.Fab")
		)
		(pad "1" smd circle
			(at -0.40005 0 270)
			(size 0 0)
			(layers "F.Cu" "F.Mask" "F.Paste")
			(net "P1V25_PEX2_CS")
		)
		(pad "2" smd circle
			(at 0.40005 0 270)
			(size 0 0)
			(layers "F.Cu" "F.Mask" "F.Paste")
			(net "GND")
		)
	)
)
